# BASEBOARD_FAB2 (Tioga Pass) — schematic netlist excerpt (pin names and nets, part order shuffled) for the footprints in the layout excerpt that follows; sources: Cadence DE-HDL packaged netlist, KiCad conversion of Wiwynn_Tioga_Pass_MB.brd

R9M21  RES  0.0 5% CHIP  pkg 0402  page 156 : A = SMB_LAN_STBY_LVC3_SDA ; B = SMB_PIROM_CPU1_SDA
R1L9  RES  100.0K 1% CHIP  pkg 0402  page 155 : A = P12V_STBY ; B = FM_CPLD_DBG_PWR_EN
R9L6  RES  1.00K 1% CHIP  pkg 0402  page 100 : A = M_L_VREF ; B = GND

(kicad_pcb
	(version 20260206)
	(generator "pcbnew")
	(generator_version "10.0")
	(general
		(thickness 1.6)
		(legacy_teardrops no)
	)
	(paper "A4")
	(title_block
		(title "Wiwynn_Tioga_Pass_MB.brd")
		(comment 1 "Tioga Pass / footprints 2390-2392 of 4770")
	)
	(layers
		(0 "F.Cu" signal "TOP")
		(4 "In1.Cu" signal "L2GND")
		(6 "In2.Cu" signal "L3")
		(8 "In3.Cu" signal "L4GND")
		(10 "In4.Cu" signal "L5")
		(12 "In5.Cu" signal "L6GND")
		(14 "In6.Cu" signal "L7VCC")
		(16 "In7.Cu" signal "L8VCC")
		(18 "In8.Cu" signal "L9GND")
		(20 "In9.Cu" signal "L10")
		(22 "In10.Cu" signal "L11GND")
		(24 "In11.Cu" signal "L12")
		(26 "In12.Cu" signal "L13GND")
		(2 "B.Cu" signal "BOTTOM")
		(9 "F.Adhes" user "F.Adhesive")
		(11 "B.Adhes" user "B.Adhesive")
		(13 "F.Paste" user "Package Geometry/Pastemask Top")
		(15 "B.Paste" user "Package Geometry/Pastemask Bottom")
		(5 "F.SilkS" user "Ref Des/Silkscreen Top")
		(7 "B.SilkS" user "Ref Des/Silkscreen Bottom")
		(1 "F.Mask" user "Board Geometry/Soldermask Top")
		(3 "B.Mask" user "Board Geometry/Soldermask Bottom")
		(17 "Dwgs.User" user "User.Drawings")
		(19 "Cmts.User" user "User.Comments")
		(21 "Eco1.User" user "User.Eco1")
		(23 "Eco2.User" user "User.Eco2")
		(25 "Edge.Cuts" user "Board Geometry/Outline")
		(27 "Margin" user)
		(31 "F.CrtYd" user "Package Geometry/Place Bound Top")
		(29 "B.CrtYd" user "Package Geometry/Place Bound Bottom")
		(35 "F.Fab" user "Ref Des/Assembly Top")
		(33 "B.Fab" user "Ref Des/Assembly Bottom")
	)
	(footprint ""
		(layer "B.Cu")
		(at 20.153884 -134.189978 -90)
		(property "Reference" "R9M21"
			(at 0 0 90)
			(layer "B.SilkS")
			(hide yes)
			(effects
				(font
					(size 1.27 1.27)
				)
				(justify mirror)
			)
		)
		(property "Value" ""
			(at 0 0 90)
			(layer "B.Fab")
			(effects
				(font
					(size 1.27 1.27)
				)
				(justify mirror)
			)
		)
		(duplicate_pad_numbers_are_jumpers no)
		(fp_poly
			(pts
				(xy 0.2794 -0.1016) (xy -0.2794 -0.1016) (xy -0.2794 0.9906) (xy 0.2794 0.9906)
			)
			(stroke
				(width 0)
				(type default)
			)
			(fill no)
			(layer "B.CrtYd")
		)
		(fp_line
			(start -0.2794 0.9906)
			(end -0.2794 -0.1016)
			(stroke
				(width 0.1)
				(type default)
			)
			(layer "B.Fab")
		)
		(fp_line
			(start 0.2794 0.9906)
			(end -0.2794 0.9906)
			(stroke
				(width 0.1)
				(type default)
			)
			(layer "B.Fab")
		)
		(fp_line
			(start -0.2794 -0.1016)
			(end 0.2794 -0.1016)
			(stroke
				(width 0.1)
				(type default)
			)
			(layer "B.Fab")
		)
		(fp_line
			(start 0.2794 -0.1016)
			(end 0.2794 0.9906)
			(stroke
				(width 0.1)
				(type default)
			)
			(layer "B.Fab")
		)
		(pad "1" smd rect
			(at 0 0 90)
			(size 0.508 0.508)
			(layers "B.Cu" "B.Mask" "B.Paste")
			(net "SMB_LAN_STBY_LVC3_SDA")
		)
		(pad "2" smd rect
			(at 0 0.889 90)
			(size 0.508 0.508)
			(layers "B.Cu" "B.Mask" "B.Paste")
			(net "SMB_PIROM_CPU1_SDA")
		)
		(zone
			(layer "B.Cu")
			(hatch none 0.5)
			(connect_pads
				(clearance 0)
			)
			(min_thickness 0.25)
			(keepout
				(tracks not_allowed)
				(vias allowed)
				(pads allowed)
				(copperpour not_allowed)
				(footprints allowed)
			)
			(placement
				(enabled no)
				(sheetname "")
			)
			(fill
				(thermal_gap 0.5)
				(thermal_bridge_width 0.5)
				(island_removal_mode 0)
			)
			(polygon
				(pts
					(xy 19.518884 -133.935978) (xy 19.518884 -134.443978) (xy 19.899884 -134.443978) (xy 19.899884 -133.935978)
				)
			)
		)
		(zone
			(layer "B.Cu")
			(hatch none 0.5)
			(connect_pads
				(clearance 0)
			)
			(min_thickness 0.25)
			(keepout
				(tracks allowed)
				(vias not_allowed)
				(pads allowed)
				(copperpour not_allowed)
				(footprints allowed)
			)
			(placement
				(enabled no)
				(sheetname "")
			)
			(fill
				(thermal_gap 0.5)
				(thermal_bridge_width 0.5)
				(island_removal_mode 0)
			)
			(polygon
				(pts
					(xy 19.899884 -133.935978) (xy 19.899884 -134.443978) (xy 19.518884 -134.443978) (xy 19.518884 -133.935978)
				)
			)
		)
	)
	(footprint ""
		(layer "B.Cu")
		(at 29.436568 -145.3642)
		(property "Reference" "R9L6"
			(at 0 0 0)
			(layer "B.SilkS")
			(hide yes)
			(effects
				(font
					(size 1.27 1.27)
				)
				(justify mirror)
			)
		)
		(property "Value" ""
			(at 0 0 0)
			(layer "B.Fab")
			(effects
				(font
					(size 1.27 1.27)
				)
				(justify mirror)
			)
		)
		(duplicate_pad_numbers_are_jumpers no)
		(fp_poly
			(pts
				(xy 0.2794 -0.1016) (xy -0.2794 -0.1016) (xy -0.2794 0.9906) (xy 0.2794 0.9906)
			)
			(stroke
				(width 0)
				(type default)
			)
			(fill no)
			(layer "B.CrtYd")
		)
		(fp_line
			(start -0.2794 -0.1016)
			(end 0.2794 -0.1016)
			(stroke
				(width 0.1)
				(type default)
			)
			(layer "B.Fab")
		)
		(fp_line
			(start -0.2794 0.9906)
			(end -0.2794 -0.1016)
			(stroke
				(width 0.1)
				(type default)
			)
			(layer "B.Fab")
		)
		(fp_line
			(start 0.2794 -0.1016)
			(end 0.2794 0.9906)
			(stroke
				(width 0.1)
				(type default)
			)
			(layer "B.Fab")
		)
		(fp_line
			(start 0.2794 0.9906)
			(end -0.2794 0.9906)
			(stroke
				(width 0.1)
				(type default)
			)
			(layer "B.Fab")
		)
		(pad "1" smd rect
			(at 0 0 180)
			(size 0.508 0.508)
			(layers "B.Cu" "B.Mask" "B.Paste")
			(net "M_L_VREF")
		)
		(pad "2" smd rect
			(at 0 0.889 180)
			(size 0.508 0.508)
			(layers "B.Cu" "B.Mask" "B.Paste")
			(net "GND")
		)
		(zone
			(layer "B.Cu")
			(hatch none 0.5)
			(connect_pads
				(clearance 0)
			)
			(min_thickness 0.25)
			(keepout
				(tracks allowed)
				(vias not_allowed)
				(pads allowed)
				(copperpour not_allowed)
				(footprints allowed)
			)
			(placement
				(enabled no)
				(sheetname "")
			)
			(fill
				(thermal_gap 0.5)
				(thermal_bridge_width 0.5)
				(island_removal_mode 0)
			)
			(polygon
				(pts
					(xy 29.690568 -145.1102) (xy 29.182568 -145.1102) (xy 29.182568 -144.7292) (xy 29.690568 -144.7292)
				)
			)
		)
		(zone
			(layer "B.Cu")
			(hatch none 0.5)
			(connect_pads
				(clearance 0)
			)
			(min_thickness 0.25)
			(keepout
				(tracks not_allowed)
				(vias allowed)
				(pads allowed)
				(copperpour not_allowed)
				(footprints allowed)
			)
			(placement
				(enabled no)
				(sheetname "")
			)
			(fill
				(thermal_gap 0.5)
				(thermal_bridge_width 0.5)
				(island_removal_mode 0)
			)
			(polygon
				(pts
					(xy 29.690568 -144.7292) (xy 29.182568 -144.7292) (xy 29.182568 -145.1102) (xy 29.690568 -145.1102)
				)
			)
		)
	)
	(footprint ""
		(layer "B.Cu")
		(at 482.5238 -151.0284)
		(property "Reference" "R1L9"
			(at 0 0 0)
			(layer "B.SilkS")
			(hide yes)
			(effects
				(font
					(size 1.27 1.27)
				)
				(justify mirror)
			)
		)
		(property "Value" ""
			(at 0 0 0)
			(layer "B.Fab")
			(effects
				(font
					(size 1.27 1.27)
				)
				(justify mirror)
			)
		)
		(duplicate_pad_numbers_are_jumpers no)
		(fp_poly
			(pts
				(xy 0.2794 -0.1016) (xy -0.2794 -0.1016) (xy -0.2794 0.9906) (xy 0.2794 0.9906)
			)
			(stroke
				(width 0)
				(type default)
			)
			(fill no)
			(layer "B.CrtYd")
		)
		(fp_line
			(start -0.2794 -0.1016)
			(end 0.2794 -0.1016)
			(stroke
				(width 0.1)
				(type default)
			)
			(layer "B.Fab")
		)
		(fp_line
			(start -0.2794 0.9906)
			(end -0.2794 -0.1016)
			(stroke
				(width 0.1)
				(type default)
			)
			(layer "B.Fab")
		)
		(fp_line
			(start 0.2794 -0.1016)
			(end 0.2794 0.9906)
			(stroke
				(width 0.1)
				(type default)
			)
			(layer "B.Fab")
		)
		(fp_line
			(start 0.2794 0.9906)
			(end -0.2794 0.9906)
			(stroke
				(width 0.1)
				(type default)
			)
			(layer "B.Fab")
		)
		(pad "1" smd rect
			(at 0 0 180)
			(size 0.508 0.508)
			(layers "B.Cu" "B.Mask" "B.Paste")
			(net "P12V_STBY")
		)
		(pad "2" smd rect
			(at 0 0.889 180)
			(size 0.508 0.508)
			(layers "B.Cu" "B.Mask" "B.Paste")
			(net "FM_CPLD_DBG_PWR_EN")
		)
		(zone
			(layer "B.Cu")
			(hatch none 0.5)
			(connect_pads
				(clearance 0)
			)
			(min_thickness 0.25)
			(keepout
				(tracks allowed)
				(vias not_allowed)
				(pads allowed)
				(copperpour not_allowed)
				(footprints allowed)
			)
			(placement
				(enabled no)
				(sheetname "")
			)
			(fill
				(thermal_gap 0.5)
				(thermal_bridge_width 0.5)
				(island_removal_mode 0)
			)
			(polygon
				(pts
					(xy 482.7778 -150.7744) (xy 482.2698 -150.7744) (xy 482.2698 -150.3934) (xy 482.7778 -150.3934)
				)
			)
		)
		(zone
			(layer "B.Cu")
			(hatch none 0.5)
			(connect_pads
				(clearance 0)
			)
			(min_thickness 0.25)
			(keepout
				(tracks not_allowed)
				(vias allowed)
				(pads allowed)
				(copperpour not_allowed)
				(footprints allowed)
			)
			(placement
				(enabled no)
				(sheetname "")
			)
			(fill
				(thermal_gap 0.5)
				(thermal_bridge_width 0.5)
				(island_removal_mode 0)
			)
			(polygon
				(pts
					(xy 482.7778 -150.3934) (xy 482.2698 -150.3934) (xy 482.2698 -150.7744) (xy 482.7778 -150.7744)
				)
			)
		)
	)
)
